(kicad_pcb
	(version 20221018)
	(generator pcbnew)
	(general
    (thickness 1.7403)
  )
	(paper "A4")
	(title_block
    (title "Data Center RDIMM DDR4 Tester")
    (date "2024-09-30")
    (rev "1.2.4")
		(comment 9 "footprints 355-364 of 690")
	)
	(layers
    (0 "F.Cu" signal)
    (1 "In1.Cu" power)
    (2 "In2.Cu" signal)
    (3 "In3.Cu" power)
    (4 "In4.Cu" power)
    (5 "In5.Cu" signal)
    (6 "In6.Cu" power)
    (7 "In7.Cu" signal)
    (8 "In8.Cu" power)
    (9 "In9.Cu" signal)
    (10 "In10.Cu" power)
    (31 "B.Cu" signal)
    (32 "B.Adhes" user "B.Adhesive")
    (33 "F.Adhes" user "F.Adhesive")
    (34 "B.Paste" user)
    (35 "F.Paste" user)
    (36 "B.SilkS" user "B.Silkscreen")
    (37 "F.SilkS" user "F.Silkscreen")
    (38 "B.Mask" user)
    (39 "F.Mask" user)
    (40 "Dwgs.User" user "User.Drawings")
    (41 "Cmts.User" user "User.Comments")
    (42 "Eco1.User" user "User.Eco1")
    (43 "Eco2.User" user "User.Eco2")
    (44 "Edge.Cuts" user)
    (45 "Margin" user)
    (46 "B.CrtYd" user "B.Courtyard")
    (47 "F.CrtYd" user "F.Courtyard")
    (48 "B.Fab" user)
    (49 "F.Fab" user)
  )
	(footprint "data-center-rdimm-ddr4-tester-footprints:mounting-hole-3mm-NPTH" (layer "F.Cu")
    (at 256.75 49)
    (property "Author" "Antmicro")
    (property "License" "Apache-2.0")
    (property "MPN" "")
    (property "Manufacturer" "")
    (property "Sheetfile" "data-center-rdimm-ddr4-tester.kicad_sch")
    (property "Sheetname" "")
    (attr through_hole)
    (fp_text reference "MP3" (at 0 -1.8) (layer "F.SilkS") hide
        (effects (font (size 0.7 0.7) (thickness 0.15)) (justify left bottom))
    )
    (fp_text value "PCB_Mount_Hole_3mm_NPTH" (at 0 2.3) (layer "F.Fab") hide
        (effects (font (size 0.7 0.7) (thickness 0.15)) (justify left bottom))
    )
    (fp_text user "${REFERENCE}" (at 0 4.749) (layer "F.Fab") hide
        (effects (font (size 0.7 0.7) (thickness 0.15)) (justify left bottom))
    )
    (fp_text user "License: Apache-2.0" (at 0 7.15) (layer "F.Fab") hide
        (effects (font (size 0.7 0.7) (thickness 0.15)) (justify left bottom))
    )
    (fp_text user "Author: Antmicro" (at 0 5.95) (layer "F.Fab") hide
        (effects (font (size 0.7 0.7) (thickness 0.15)) (justify left bottom))
    )
    (pad "" np_thru_hole circle (at 0 0) (size 3 3) (drill 3) (layers "*.Cu" "*.Mask"))
  )
	(footprint "data-center-rdimm-ddr4-tester-footprints:R_0201" (layer "F.Cu")
    (at 155.29 104.29 90)
    (descr "Resistor SMD 0201")
    (tags "resistor SMD 0201")
    (property "Author" "Antmicro")
    (property "License" "Apache-2.0")
    (property "MPN" "CR0201-FX-0R00GLF")
    (property "Manufacturer" "Bourns")
    (property "Sheetfile" "ethernet.kicad_sch")
    (property "Sheetname" "Ethernet")
    (property "Tolerance" "1%")
    (property "Val" "0R")
    (property "ki_description" "0R resistor in 0201 package with 1% tolerance")
    (attr smd)
    (fp_text reference "R98" (at 0.6 0.37 90) (layer "F.SilkS")
        (effects (font (size 0.7 0.7) (thickness 0.15)) (justify left bottom))
    )
    (fp_text value "R_0R_0201" (at 0 1.25 90) (layer "F.Fab") hide
        (effects (font (size 0.7 0.7) (thickness 0.15)) (justify left bottom))
    )
    (fp_text user "License: Apache-2.0" (at -0.71 4.25 90) (layer "F.Fab") hide
        (effects (font (size 0.7 0.7) (thickness 0.15)) (justify left bottom))
    )
    (fp_text user "Author: Antmicro" (at -0.71 5.25 90) (layer "F.Fab") hide
        (effects (font (size 0.7 0.7) (thickness 0.15)) (justify left bottom))
    )
    (fp_text user "${REFERENCE}" (at -0.71 3.25 90) (layer "F.Fab") hide
        (effects (font (size 0.7 0.7) (thickness 0.15)) (justify left bottom))
    )
    (fp_rect (start -0.71 -0.36) (end 0.71 0.36)
      (stroke (width 0.05) (type solid)) (fill none) (layer "F.CrtYd"))
    (fp_rect (start -0.3 -0.15) (end 0.298 0.148)
      (stroke (width 0.15) (type solid)) (fill none) (layer "F.Fab"))
    (pad "" smd roundrect (at -0.346 0 90) (size 0.318 0.36) (layers "F.Paste") (roundrect_rratio 0.25))
    (pad "" smd roundrect (at 0.344 0 90) (size 0.318 0.36) (layers "F.Paste") (roundrect_rratio 0.25))
    (pad "1" smd roundrect (at -0.32 0 90) (size 0.46 0.4) (layers "F.Cu" "F.Mask") (roundrect_rratio 0.25)
      (net 825 "/Ethernet/ETH1_BP_N") (pintype "passive"))
    (pad "2" smd roundrect (at 0.32 0 90) (size 0.46 0.4) (layers "F.Cu" "F.Mask") (roundrect_rratio 0.25)
      (net 173 "/Ethernet/ETH1_N") (pintype "passive"))
  )
	(footprint "data-center-rdimm-ddr4-tester-footprints:C_0402_1005Metric" (layer "F.Cu")
    (at 202 123.3 180)
    (descr "Capacitor SMD 0402")
    (tags "capacitor SMD 0402")
    (property "Author" "Antmicro")
    (property "Dielectric" "X5R")
    (property "License" "Apache-2.0")
    (property "MPN" "GRM155R61H104KE14D")
    (property "Manufacturer" "Murata")
    (property "Sheetfile" "interfaces.kicad_sch")
    (property "Sheetname" "Interfaces")
    (property "Val" "100n")
    (property "Voltage" "50V")
    (property "ki_description" " ")
    (attr smd)
    (fp_text reference "C311" (at -0.76 -0.39 180) (layer "F.SilkS")
        (effects (font (size 0.7 0.7) (thickness 0.15)) (justify left bottom))
    )
    (fp_text value "C_100n_0402" (at 0 1.4 180) (layer "F.Fab") hide
        (effects (font (size 0.7 0.7) (thickness 0.15)) (justify left bottom))
    )
    (fp_text user "License: Apache-2.0" (at -0.932 5.17 180) (layer "F.Fab") hide
        (effects (font (size 0.7 0.7) (thickness 0.15)) (justify left bottom))
    )
    (fp_text user "Author: Antmicro" (at -0.932 4.17 180) (layer "F.Fab") hide
        (effects (font (size 0.7 0.7) (thickness 0.15)) (justify left bottom))
    )
    (fp_text user "${REFERENCE}" (at -0.932 3.168 180) (layer "F.Fab") hide
        (effects (font (size 0.7 0.7) (thickness 0.15)) (justify left bottom))
    )
    (fp_rect (start -0.94 -0.47) (end 0.94 0.47)
      (stroke (width 0.05) (type solid)) (fill none) (layer "F.CrtYd"))
    (fp_rect (start -0.499 -0.249) (end 0.499 0.249)
      (stroke (width 0.15) (type solid)) (fill none) (layer "F.Fab"))
    (pad "1" smd roundrect (at -0.484 0 180) (size 0.59 0.64) (layers "F.Cu" "F.Paste" "F.Mask") (roundrect_rratio 0.25)
      (net 863 "GND1") (pintype "passive"))
    (pad "2" smd roundrect (at 0.484 0 180) (size 0.59 0.64) (layers "F.Cu" "F.Paste" "F.Mask") (roundrect_rratio 0.25)
      (net 9 "GND") (pintype "passive"))
  )
	(footprint "data-center-rdimm-ddr4-tester-footprints:C_0402_1005Metric" (layer "F.Cu")
    (at 153.67 105.01 -90)
    (descr "Capacitor SMD 0402")
    (tags "capacitor SMD 0402")
    (property "Author" "Antmicro")
    (property "DNP" "DNP")
    (property "Dielectric" "X5R")
    (property "License" "Apache-2.0")
    (property "MPN" "GRM155R61H104KE14D")
    (property "Manufacturer" "Murata")
    (property "Sheetfile" "ethernet.kicad_sch")
    (property "Sheetname" "Ethernet")
    (property "Val" "100n")
    (property "Voltage" "50V")
    (property "dnp" "")
    (property "exclude_from_bom" "")
    (property "ki_description" " ")
    (attr exclude_from_pos_files exclude_from_bom)
    (fp_text reference "C288" (at 1.23 0.53 -90) (layer "F.SilkS")
        (effects (font (size 0.7 0.7) (thickness 0.15)) (justify left bottom))
    )
    (fp_text value "C_100n_0402" (at 0 1.4 -90) (layer "F.Fab") hide
        (effects (font (size 0.7 0.7) (thickness 0.15)) (justify left bottom))
    )
    (fp_text user "License: Apache-2.0" (at -0.932 5.17 -90) (layer "F.Fab") hide
        (effects (font (size 0.7 0.7) (thickness 0.15)) (justify left bottom))
    )
    (fp_text user "${REFERENCE}" (at -0.932 3.168 -90) (layer "F.Fab") hide
        (effects (font (size 0.7 0.7) (thickness 0.15)) (justify left bottom))
    )
    (fp_text user "Author: Antmicro" (at -0.932 4.17 -90) (layer "F.Fab") hide
        (effects (font (size 0.7 0.7) (thickness 0.15)) (justify left bottom))
    )
    (fp_rect (start -0.94 -0.47) (end 0.94 0.47)
      (stroke (width 0.05) (type solid)) (fill none) (layer "F.CrtYd"))
    (fp_rect (start -0.499 -0.249) (end 0.499 0.249)
      (stroke (width 0.15) (type solid)) (fill none) (layer "F.Fab"))
    (pad "1" smd roundrect (at -0.484 0 270) (size 0.59 0.64) (layers "F.Cu" "F.Paste" "F.Mask") (roundrect_rratio 0.25)
      (net 143 "3V3_SYS") (pintype "passive"))
    (pad "2" smd roundrect (at 0.484 0 270) (size 0.59 0.64) (layers "F.Cu" "F.Paste" "F.Mask") (roundrect_rratio 0.25)
      (net 9 "GND") (pintype "passive"))
  )
	(footprint "data-center-rdimm-ddr4-tester-footprints:PROBE_PAD_1206" (layer "F.Cu")
    (at 134.7 133.45 180)
    (property "Author" "Antmicro")
    (property "License" "Apache-2.0")
    (property "MPN" "RCW-0C")
    (property "Manufacturer" "TE Connectivity")
    (property "Sheetfile" "supply.kicad_sch")
    (property "Sheetname" "Supply")
    (property "ki_description" "SMD Circuit Probe Pad 1206")
    (attr smd)
    (fp_text reference "GND1" (at 1.52 1.19 180) (layer "F.SilkS")
        (effects (font (size 0.7 0.7) (thickness 0.15)) (justify left bottom))
    )
    (fp_text value "TestPoint_Probe_1206_RCW-0C" (at 0 2.112 180) (layer "F.Fab") hide
        (effects (font (size 0.7 0.7) (thickness 0.15)) (justify left bottom))
    )
    (fp_text user "License: Apache-2.0" (at -1.95 6.512 180) (layer "F.Fab") hide
        (effects (font (size 0.7 0.7) (thickness 0.15)) (justify left bottom))
    )
    (fp_text user "Author: Antmicro" (at -1.95 5.312 180) (layer "F.Fab") hide
        (effects (font (size 0.7 0.7) (thickness 0.15)) (justify left bottom))
    )
    (fp_text user "${REFERENCE}" (at -1.95 4.112 180) (layer "F.Fab") hide
        (effects (font (size 0.7 0.7) (thickness 0.15)) (justify left bottom))
    )
    (fp_line (start -1.78 -0.92) (end -1.78 -0.419)
      (stroke (width 0.15) (type solid)) (layer "F.SilkS"))
    (fp_line (start -1.78 -0.92) (end -1.28 -0.92)
      (stroke (width 0.15) (type solid)) (layer "F.SilkS"))
    (fp_line (start -1.78 0.541) (end -1.78 1.04)
      (stroke (width 0.15) (type solid)) (layer "F.SilkS"))
    (fp_line (start -1.78 1.04) (end -1.28 1.04)
      (stroke (width 0.15) (type solid)) (layer "F.SilkS"))
    (fp_line (start 1.779 1.042) (end 1.28 1.042)
      (stroke (width 0.15) (type solid)) (layer "F.SilkS"))
    (fp_line (start 1.779 1.042) (end 1.779 0.542)
      (stroke (width 0.15) (type solid)) (layer "F.SilkS"))
    (fp_line (start 1.78 -0.92) (end 1.28 -0.92)
      (stroke (width 0.15) (type solid)) (layer "F.SilkS"))
    (fp_line (start 1.78 -0.92) (end 1.78 -0.419)
      (stroke (width 0.15) (type solid)) (layer "F.SilkS"))
    (fp_line (start -1.95 -1.08) (end -1.95 1.18)
      (stroke (width 0.05) (type solid)) (layer "F.CrtYd"))
    (fp_line (start 1.93 -1.08) (end -1.95 -1.08)
      (stroke (width 0.05) (type solid)) (layer "F.CrtYd"))
    (fp_line (start 1.93 -1.08) (end 1.93 1.18)
      (stroke (width 0.05) (type solid)) (layer "F.CrtYd"))
    (fp_line (start 1.93 1.18) (end -1.95 1.18)
      (stroke (width 0.05) (type solid)) (layer "F.CrtYd"))
    (fp_line (start -1.601 0.861) (end -1.601 -0.738)
      (stroke (width 0.15) (type solid)) (layer "F.Fab"))
    (fp_line (start 1.6 -0.738) (end -1.601 -0.738)
      (stroke (width 0.15) (type solid)) (layer "F.Fab"))
    (fp_line (start 1.6 0.861) (end -1.601 0.861)
      (stroke (width 0.15) (type solid)) (layer "F.Fab"))
    (fp_line (start 1.6 0.861) (end 1.6 -0.738)
      (stroke (width 0.15) (type solid)) (layer "F.Fab"))
    (pad "1" smd rect (at 0 0.061 180) (size 3.4 1.8) (layers "F.Cu" "F.Paste" "F.Mask")
      (net 9 "GND") (pinfunction "1") (pintype "passive"))
  )
	(footprint "data-center-rdimm-ddr4-tester-footprints:Testpoint_smd_1mm" (layer "F.Cu")
    (at 230.9 125.3 180)
    (property "Author" "Antmicro")
    (property "License" "Apache-2.0")
    (property "MPN" "")
    (property "Manufacturer" "")
    (property "Sheetfile" "supply.kicad_sch")
    (property "Sheetname" "Supply")
    (property "ki_description" "Test Point 1mm")
    (attr exclude_from_pos_files)
    (fp_text reference "TP14" (at 0.8 -1.43 180) (layer "F.SilkS")
        (effects (font (size 0.7 0.7) (thickness 0.15)) (justify left bottom))
    )
    (fp_text value "TP_1mm_SMD" (at 0 1.4 180) (layer "F.Fab") hide
        (effects (font (size 0.7 0.7) (thickness 0.15)) (justify left bottom))
    )
    (fp_text user "${REFERENCE}" (at -0.5 2.8 180) (layer "F.Fab") hide
        (effects (font (size 0.7 0.7) (thickness 0.15)) (justify left bottom))
    )
    (fp_text user "License: Apache-2.0" (at -0.5 5.2 180) (layer "F.Fab") hide
        (effects (font (size 0.7 0.7) (thickness 0.15)) (justify left bottom))
    )
    (fp_text user "Author: Antmicro" (at -0.5 4 180) (layer "F.Fab") hide
        (effects (font (size 0.7 0.7) (thickness 0.15)) (justify left bottom))
    )
    (pad "1" smd circle (at 0 0 180) (size 1 1) (layers "F.Cu" "F.Mask")
      (net 119 "/Supply/~{INT}") (pinfunction "1") (pintype "passive"))
  )
	(footprint "data-center-rdimm-ddr4-tester-footprints:C_0402_1005Metric" (layer "F.Cu")
    (at 254.71 76.635 180)
    (descr "Capacitor SMD 0402")
    (tags "capacitor SMD 0402")
    (property "Author" "Antmicro")
    (property "Dielectric" "X5R")
    (property "License" "Apache-2.0")
    (property "MPN" "GRM155R61H104KE14D")
    (property "Manufacturer" "Murata")
    (property "Sheetfile" "fmc_hpc.kicad_sch")
    (property "Sheetname" "FMC HPC")
    (property "Val" "100n")
    (property "Voltage" "50V")
    (property "ki_description" " ")
    (attr smd)
    (fp_text reference "C270" (at -0.78 -0.375 180) (layer "F.SilkS")
        (effects (font (size 0.7 0.7) (thickness 0.15)) (justify left bottom))
    )
    (fp_text value "C_100n_0402" (at 0 1.4 180) (layer "F.Fab") hide
        (effects (font (size 0.7 0.7) (thickness 0.15)) (justify left bottom))
    )
    (fp_text user "Author: Antmicro" (at -0.932 4.17 180) (layer "F.Fab") hide
        (effects (font (size 0.7 0.7) (thickness 0.15)) (justify left bottom))
    )
    (fp_text user "${REFERENCE}" (at -0.932 3.168 180) (layer "F.Fab") hide
        (effects (font (size 0.7 0.7) (thickness 0.15)) (justify left bottom))
    )
    (fp_text user "License: Apache-2.0" (at -0.932 5.17 180) (layer "F.Fab") hide
        (effects (font (size 0.7 0.7) (thickness 0.15)) (justify left bottom))
    )
    (fp_rect (start -0.94 -0.47) (end 0.94 0.47)
      (stroke (width 0.05) (type solid)) (fill none) (layer "F.CrtYd"))
    (fp_rect (start -0.499 -0.249) (end 0.499 0.249)
      (stroke (width 0.15) (type solid)) (fill none) (layer "F.Fab"))
    (pad "1" smd roundrect (at -0.484 0 180) (size 0.59 0.64) (layers "F.Cu" "F.Paste" "F.Mask") (roundrect_rratio 0.25)
      (net 482 "/FMC HPC/GTX_TX5_C_N") (pintype "passive"))
    (pad "2" smd roundrect (at 0.484 0 180) (size 0.59 0.64) (layers "F.Cu" "F.Paste" "F.Mask") (roundrect_rratio 0.25)
      (net 483 "GTX_TX5_N") (pintype "passive"))
  )
	(footprint "data-center-rdimm-ddr4-tester-footprints:C_0402_1005Metric" (layer "F.Cu")
    (at 254.71 91.875 180)
    (descr "Capacitor SMD 0402")
    (tags "capacitor SMD 0402")
    (property "Author" "Antmicro")
    (property "Dielectric" "X5R")
    (property "License" "Apache-2.0")
    (property "MPN" "GRM155R61H104KE14D")
    (property "Manufacturer" "Murata")
    (property "Sheetfile" "fmc_hpc.kicad_sch")
    (property "Sheetname" "FMC HPC")
    (property "Val" "100n")
    (property "Voltage" "50V")
    (property "ki_description" " ")
    (attr smd)
    (fp_text reference "C264" (at -0.8 -0.385 180) (layer "F.SilkS")
        (effects (font (size 0.7 0.7) (thickness 0.15)) (justify left bottom))
    )
    (fp_text value "C_100n_0402" (at 0 1.4 180) (layer "F.Fab") hide
        (effects (font (size 0.7 0.7) (thickness 0.15)) (justify left bottom))
    )
    (fp_text user "${REFERENCE}" (at -0.932 3.168 180) (layer "F.Fab") hide
        (effects (font (size 0.7 0.7) (thickness 0.15)) (justify left bottom))
    )
    (fp_text user "License: Apache-2.0" (at -0.932 5.17 180) (layer "F.Fab") hide
        (effects (font (size 0.7 0.7) (thickness 0.15)) (justify left bottom))
    )
    (fp_text user "Author: Antmicro" (at -0.932 4.17 180) (layer "F.Fab") hide
        (effects (font (size 0.7 0.7) (thickness 0.15)) (justify left bottom))
    )
    (fp_rect (start -0.94 -0.47) (end 0.94 0.47)
      (stroke (width 0.05) (type solid)) (fill none) (layer "F.CrtYd"))
    (fp_rect (start -0.499 -0.249) (end 0.499 0.249)
      (stroke (width 0.15) (type solid)) (fill none) (layer "F.Fab"))
    (pad "1" smd roundrect (at -0.484 0 180) (size 0.59 0.64) (layers "F.Cu" "F.Paste" "F.Mask") (roundrect_rratio 0.25)
      (net 438 "/FMC HPC/GTX_TX2_C_N") (pintype "passive"))
    (pad "2" smd roundrect (at 0.484 0 180) (size 0.59 0.64) (layers "F.Cu" "F.Paste" "F.Mask") (roundrect_rratio 0.25)
      (net 439 "GTX_TX2_N") (pintype "passive"))
  )
	(footprint "data-center-rdimm-ddr4-tester-footprints:R_0201" (layer "F.Cu")
    (at 158.55 109.035 90)
    (descr "Resistor SMD 0201")
    (tags "resistor SMD 0201")
    (property "Author" "Antmicro")
    (property "License" "Apache-2.0")
    (property "MPN" "CR0201-FX-0R00GLF")
    (property "Manufacturer" "Bourns")
    (property "Sheetfile" "ethernet.kicad_sch")
    (property "Sheetname" "Ethernet")
    (property "Tolerance" "1%")
    (property "Val" "0R")
    (property "ki_description" "0R resistor in 0201 package with 1% tolerance")
    (attr smd)
    (fp_text reference "R108" (at -3.465 0.35 90) (layer "F.SilkS")
        (effects (font (size 0.7 0.7) (thickness 0.15)) (justify left bottom))
    )
    (fp_text value "R_0R_0201" (at 0 1.25 90) (layer "F.Fab") hide
        (effects (font (size 0.7 0.7) (thickness 0.15)) (justify left bottom))
    )
    (fp_text user "License: Apache-2.0" (at -0.71 4.25 90) (layer "F.Fab") hide
        (effects (font (size 0.7 0.7) (thickness 0.15)) (justify left bottom))
    )
    (fp_text user "${REFERENCE}" (at -0.71 3.25 90) (layer "F.Fab") hide
        (effects (font (size 0.7 0.7) (thickness 0.15)) (justify left bottom))
    )
    (fp_text user "Author: Antmicro" (at -0.71 5.25 90) (layer "F.Fab") hide
        (effects (font (size 0.7 0.7) (thickness 0.15)) (justify left bottom))
    )
    (fp_rect (start -0.71 -0.36) (end 0.71 0.36)
      (stroke (width 0.05) (type solid)) (fill none) (layer "F.CrtYd"))
    (fp_rect (start -0.3 -0.15) (end 0.298 0.148)
      (stroke (width 0.15) (type solid)) (fill none) (layer "F.Fab"))
    (pad "" smd roundrect (at -0.346 0 90) (size 0.318 0.36) (layers "F.Paste") (roundrect_rratio 0.25))
    (pad "" smd roundrect (at 0.344 0 90) (size 0.318 0.36) (layers "F.Paste") (roundrect_rratio 0.25))
    (pad "1" smd roundrect (at -0.32 0 90) (size 0.46 0.4) (layers "F.Cu" "F.Mask") (roundrect_rratio 0.25)
      (net 567 "/Ethernet/INT_ETH2_N") (pintype "passive"))
    (pad "2" smd roundrect (at 0.32 0 90) (size 0.46 0.4) (layers "F.Cu" "F.Mask") (roundrect_rratio 0.25)
      (net 827 "/Ethernet/ETH2_BP_N") (pintype "passive"))
  )
	(footprint "data-center-rdimm-ddr4-tester-footprints:C_0402_1005Metric" (layer "F.Cu")
    (at 256.18 80.181)
    (descr "Capacitor SMD 0402")
    (tags "capacitor SMD 0402")
    (property "Author" "Antmicro")
    (property "Dielectric" "X5R")
    (property "License" "Apache-2.0")
    (property "MPN" "GRM155R61H104KE14D")
    (property "Manufacturer" "Murata")
    (property "Sheetfile" "fmc_hpc.kicad_sch")
    (property "Sheetname" "FMC HPC")
    (property "Val" "100n")
    (property "Voltage" "50V")
    (property "ki_description" " ")
    (attr smd)
    (fp_text reference "C271" (at 0.74 0.339) (layer "F.SilkS")
        (effects (font (size 0.7 0.7) (thickness 0.15)) (justify left bottom))
    )
    (fp_text value "C_100n_0402" (at 0 1.4) (layer "F.Fab") hide
        (effects (font (size 0.7 0.7) (thickness 0.15)) (justify left bottom))
    )
    (fp_text user "Author: Antmicro" (at -0.932 4.17) (layer "F.Fab") hide
        (effects (font (size 0.7 0.7) (thickness 0.15)) (justify left bottom))
    )
    (fp_text user "${REFERENCE}" (at -0.932 3.168) (layer "F.Fab") hide
        (effects (font (size 0.7 0.7) (thickness 0.15)) (justify left bottom))
    )
    (fp_text user "License: Apache-2.0" (at -0.932 5.17) (layer "F.Fab") hide
        (effects (font (size 0.7 0.7) (thickness 0.15)) (justify left bottom))
    )
    (fp_rect (start -0.94 -0.47) (end 0.94 0.47)
      (stroke (width 0.05) (type solid)) (fill none) (layer "F.CrtYd"))
    (fp_rect (start -0.499 -0.249) (end 0.499 0.249)
      (stroke (width 0.15) (type solid)) (fill none) (layer "F.Fab"))
    (pad "1" smd roundrect (at -0.484 0) (size 0.59 0.64) (layers "F.Cu" "F.Paste" "F.Mask") (roundrect_rratio 0.25)
      (net 497 "/FMC HPC/GTX_TX6_C_P") (pintype "passive"))
    (pad "2" smd roundrect (at 0.484 0) (size 0.59 0.64) (layers "F.Cu" "F.Paste" "F.Mask") (roundrect_rratio 0.25)
      (net 498 "GTX_TX6_P") (pintype "passive"))
  )
)
